(kicad_pcb
	(version 20260206)
	(generator "pcbnew")
	(generator_version "10.0")
	(general
		(thickness 1.6)
		(legacy_teardrops no)
	)
	(paper "A4")
	(title_block
		(title "01162023_DA0F0TEBIF0_F0T_Expander_BD_F_brd_V02_OCP.brd")
		(comment 1 "Grand Teton / footprints 5892-5895 of 9728")
	)
	(layers
		(0 "F.Cu" signal "TOP")
		(4 "In1.Cu" signal "GND")
		(6 "In2.Cu" signal "VCC")
		(8 "In3.Cu" signal "VCC1")
		(10 "In4.Cu" signal "GND1")
		(12 "In5.Cu" signal "IN1")
		(14 "In6.Cu" signal "GND2")
		(16 "In7.Cu" signal "IN2")
		(18 "In8.Cu" signal "GND3")
		(20 "In9.Cu" signal "IN3")
		(22 "In10.Cu" signal "GND4")
		(24 "In11.Cu" signal "IN4")
		(26 "In12.Cu" signal "GND5")
		(28 "In13.Cu" signal "IN5")
		(30 "In14.Cu" signal "GND6")
		(32 "In15.Cu" signal "IN6")
		(34 "In16.Cu" signal "GND7")
		(2 "B.Cu" signal "BOTTOM")
		(9 "F.Adhes" user "F.Adhesive")
		(11 "B.Adhes" user "B.Adhesive")
		(13 "F.Paste" user "Package Geometry/Pastemask Top")
		(15 "B.Paste" user "Package Geometry/Pastemask Bottom")
		(5 "F.SilkS" user "Ref Des/Silkscreen Top")
		(7 "B.SilkS" user "Ref Des/Silkscreen Bottom")
		(1 "F.Mask" user "Board Geometry/Soldermask Top")
		(3 "B.Mask" user "Board Geometry/Soldermask Bottom")
		(17 "Dwgs.User" user "User.Drawings")
		(19 "Cmts.User" user "User.Comments")
		(21 "Eco1.User" user "User.Eco1")
		(23 "Eco2.User" user "User.Eco2")
		(25 "Edge.Cuts" user "Board Geometry/Outline")
		(27 "Margin" user)
		(31 "F.CrtYd" user "Package Geometry/Place Bound Top")
		(29 "B.CrtYd" user "Package Geometry/Place Bound Bottom")
		(35 "F.Fab" user "Ref Des/Assembly Top")
		(33 "B.Fab" user "Ref Des/Assembly Bottom")
	)
	(footprint ""
		(layer "F.Cu")
		(at 362.336334 -240.68913 180)
		(property "Reference" "R6405"
			(at 0 0 180)
			(layer "F.SilkS")
			(hide yes)
			(effects
				(font
					(size 1.27 1.27)
				)
			)
		)
		(property "Value" ""
			(at 0 0 180)
			(layer "F.Fab")
			(effects
				(font
					(size 1.27 1.27)
				)
			)
		)
		(duplicate_pad_numbers_are_jumpers no)
		(fp_line
			(start 0.7874 0.4064)
			(end -0.7874 0.4064)
			(stroke
				(width 0.1524)
				(type default)
			)
			(layer "F.SilkS")
		)
		(fp_line
			(start 0.7874 -0.4064)
			(end 0.7874 0.4064)
			(stroke
				(width 0.1524)
				(type default)
			)
			(layer "F.SilkS")
		)
		(fp_line
			(start -0.7874 0.4064)
			(end -0.7874 -0.4064)
			(stroke
				(width 0.1524)
				(type default)
			)
			(layer "F.SilkS")
		)
		(fp_line
			(start -0.7874 -0.4064)
			(end 0.7874 -0.4064)
			(stroke
				(width 0.1524)
				(type default)
			)
			(layer "F.SilkS")
		)
		(fp_line
			(start 0.67945 0.3048)
			(end 0.120396 0.3048)
			(stroke
				(width 0.1)
				(type default)
			)
			(layer "F.Fab")
		)
		(fp_line
			(start 0.67945 -0.3048)
			(end 0.67945 0.3048)
			(stroke
				(width 0.1)
				(type default)
			)
			(layer "F.Fab")
		)
		(fp_line
			(start 0.12065 -0.2794)
			(end 0.12065 -0.3048)
			(stroke
				(width 0.1)
				(type default)
			)
			(layer "F.Fab")
		)
		(fp_line
			(start 0.12065 -0.3048)
			(end 0.67945 -0.3048)
			(stroke
				(width 0.1)
				(type default)
			)
			(layer "F.Fab")
		)
		(fp_line
			(start 0.120396 0.3048)
			(end 0.120396 0.2794)
			(stroke
				(width 0.1)
				(type default)
			)
			(layer "F.Fab")
		)
		(fp_line
			(start 0.120396 0.2794)
			(end -0.12065 0.2794)
			(stroke
				(width 0.1)
				(type default)
			)
			(layer "F.Fab")
		)
		(fp_line
			(start -0.12065 0.3048)
			(end -0.67945 0.3048)
			(stroke
				(width 0.1)
				(type default)
			)
			(layer "F.Fab")
		)
		(fp_line
			(start -0.12065 0.2794)
			(end -0.12065 0.3048)
			(stroke
				(width 0.1)
				(type default)
			)
			(layer "F.Fab")
		)
		(fp_line
			(start -0.12065 -0.2794)
			(end 0.12065 -0.2794)
			(stroke
				(width 0.1)
				(type default)
			)
			(layer "F.Fab")
		)
		(fp_line
			(start -0.12065 -0.305054)
			(end -0.12065 -0.2794)
			(stroke
				(width 0.1)
				(type default)
			)
			(layer "F.Fab")
		)
		(fp_line
			(start -0.67945 0.3048)
			(end -0.67945 -0.305054)
			(stroke
				(width 0.1)
				(type default)
			)
			(layer "F.Fab")
		)
		(fp_line
			(start -0.67945 -0.305054)
			(end -0.12065 -0.305054)
			(stroke
				(width 0.1)
				(type default)
			)
			(layer "F.Fab")
		)
		(pad "1" smd circle
			(at -0.40005 0 180)
			(size 0 0)
			(layers "F.Cu" "F.Mask" "F.Paste")
			(net "PWRGD_P3V3_AUX_BUF")
		)
		(pad "2" smd circle
			(at 0.40005 0 180)
			(size 0 0)
			(layers "F.Cu" "F.Mask" "F.Paste")
			(net "PWRGD_P3V3_AUX_BUF_R")
		)
	)
	(footprint ""
		(layer "F.Cu")
		(at 387.580632 -136.729724)
		(property "Reference" "C667"
			(at 0 0 0)
			(layer "F.SilkS")
			(hide yes)
			(effects
				(font
					(size 1.27 1.27)
				)
			)
		)
		(property "Value" ""
			(at 0 0 0)
			(layer "F.Fab")
			(effects
				(font
					(size 1.27 1.27)
				)
			)
		)
		(duplicate_pad_numbers_are_jumpers no)
		(fp_line
			(start -0.299974 -0.150114)
			(end 0.299974 -0.150114)
			(stroke
				(width 0.1)
				(type default)
			)
			(layer "F.Fab")
		)
		(fp_line
			(start -0.299974 0.150114)
			(end -0.299974 -0.150114)
			(stroke
				(width 0.1)
				(type default)
			)
			(layer "F.Fab")
		)
		(fp_line
			(start 0.299974 -0.150114)
			(end 0.299974 0.150114)
			(stroke
				(width 0.1)
				(type default)
			)
			(layer "F.Fab")
		)
		(fp_line
			(start 0.299974 0.150114)
			(end -0.299974 0.150114)
			(stroke
				(width 0.1)
				(type default)
			)
			(layer "F.Fab")
		)
		(pad "1" smd rect
			(at -0.2667 0)
			(size 0.3048 0.381)
			(layers "F.Cu" "F.Mask" "F.Paste")
			(net "P5E_PEX3_STN1_TX_DP<31>")
		)
		(pad "2" smd rect
			(at 0.2667 0)
			(size 0.3048 0.381)
			(layers "F.Cu" "F.Mask" "F.Paste")
			(net "P5E_PEX3_STN1_TX_C_DP<31>")
		)
	)
	(footprint ""
		(layer "F.Cu")
		(at 224.851976 -374.106186 180)
		(property "Reference" "PR27"
			(at 0 0 180)
			(layer "F.SilkS")
			(hide yes)
			(effects
				(font
					(size 1.27 1.27)
				)
			)
		)
		(property "Value" ""
			(at 0 0 180)
			(layer "F.Fab")
			(effects
				(font
					(size 1.27 1.27)
				)
			)
		)
		(duplicate_pad_numbers_are_jumpers no)
		(fp_line
			(start 0.7874 0.4064)
			(end -0.7874 0.4064)
			(stroke
				(width 0.1524)
				(type default)
			)
			(layer "F.SilkS")
		)
		(fp_line
			(start 0.7874 -0.4064)
			(end 0.7874 0.4064)
			(stroke
				(width 0.1524)
				(type default)
			)
			(layer "F.SilkS")
		)
		(fp_line
			(start -0.7874 0.4064)
			(end -0.7874 -0.4064)
			(stroke
				(width 0.1524)
				(type default)
			)
			(layer "F.SilkS")
		)
		(fp_line
			(start -0.7874 -0.4064)
			(end 0.7874 -0.4064)
			(stroke
				(width 0.1524)
				(type default)
			)
			(layer "F.SilkS")
		)
		(fp_line
			(start 0.67945 0.3048)
			(end 0.120396 0.3048)
			(stroke
				(width 0.1)
				(type default)
			)
			(layer "F.Fab")
		)
		(fp_line
			(start 0.67945 -0.3048)
			(end 0.67945 0.3048)
			(stroke
				(width 0.1)
				(type default)
			)
			(layer "F.Fab")
		)
		(fp_line
			(start 0.12065 -0.2794)
			(end 0.12065 -0.3048)
			(stroke
				(width 0.1)
				(type default)
			)
			(layer "F.Fab")
		)
		(fp_line
			(start 0.12065 -0.3048)
			(end 0.67945 -0.3048)
			(stroke
				(width 0.1)
				(type default)
			)
			(layer "F.Fab")
		)
		(fp_line
			(start 0.120396 0.3048)
			(end 0.120396 0.2794)
			(stroke
				(width 0.1)
				(type default)
			)
			(layer "F.Fab")
		)
		(fp_line
			(start 0.120396 0.2794)
			(end -0.12065 0.2794)
			(stroke
				(width 0.1)
				(type default)
			)
			(layer "F.Fab")
		)
		(fp_line
			(start -0.12065 0.3048)
			(end -0.67945 0.3048)
			(stroke
				(width 0.1)
				(type default)
			)
			(layer "F.Fab")
		)
		(fp_line
			(start -0.12065 0.2794)
			(end -0.12065 0.3048)
			(stroke
				(width 0.1)
				(type default)
			)
			(layer "F.Fab")
		)
		(fp_line
			(start -0.12065 -0.2794)
			(end 0.12065 -0.2794)
			(stroke
				(width 0.1)
				(type default)
			)
			(layer "F.Fab")
		)
		(fp_line
			(start -0.12065 -0.305054)
			(end -0.12065 -0.2794)
			(stroke
				(width 0.1)
				(type default)
			)
			(layer "F.Fab")
		)
		(fp_line
			(start -0.67945 0.3048)
			(end -0.67945 -0.305054)
			(stroke
				(width 0.1)
				(type default)
			)
			(layer "F.Fab")
		)
		(fp_line
			(start -0.67945 -0.305054)
			(end -0.12065 -0.305054)
			(stroke
				(width 0.1)
				(type default)
			)
			(layer "F.Fab")
		)
		(pad "1" smd circle
			(at -0.40005 0 180)
			(size 0 0)
			(layers "F.Cu" "F.Mask" "F.Paste")
			(net "AGND_HSC")
		)
		(pad "2" smd circle
			(at 0.40005 0 180)
			(size 0 0)
			(layers "F.Cu" "F.Mask" "F.Paste")
			(net "HSC_MODE_1")
		)
	)
	(footprint ""
		(layer "F.Cu")
		(at 133.29158 -152.71115 90)
		(property "Reference" "R702"
			(at 0 0 90)
			(layer "F.SilkS")
			(hide yes)
			(effects
				(font
					(size 1.27 1.27)
				)
			)
		)
		(property "Value" ""
			(at 0 0 90)
			(layer "F.Fab")
			(effects
				(font
					(size 1.27 1.27)
				)
			)
		)
		(duplicate_pad_numbers_are_jumpers no)
		(fp_line
			(start 0.7874 -0.4064)
			(end 0.7874 0.4064)
			(stroke
				(width 0.1524)
				(type default)
			)
			(layer "F.SilkS")
		)
		(fp_line
			(start -0.7874 -0.4064)
			(end 0.7874 -0.4064)
			(stroke
				(width 0.1524)
				(type default)
			)
			(layer "F.SilkS")
		)
		(fp_line
			(start 0.7874 0.4064)
			(end -0.7874 0.4064)
			(stroke
				(width 0.1524)
				(type default)
			)
			(layer "F.SilkS")
		)
		(fp_line
			(start -0.7874 0.4064)
			(end -0.7874 -0.4064)
			(stroke
				(width 0.1524)
				(type default)
			)
			(layer "F.SilkS")
		)
		(fp_line
			(start -0.12065 -0.305054)
			(end -0.12065 -0.2794)
			(stroke
				(width 0.1)
				(type default)
			)
			(layer "F.Fab")
		)
		(fp_line
			(start -0.67945 -0.305054)
			(end -0.12065 -0.305054)
			(stroke
				(width 0.1)
				(type default)
			)
			(layer "F.Fab")
		)
		(fp_line
			(start 0.67945 -0.3048)
			(end 0.67945 0.3048)
			(stroke
				(width 0.1)
				(type default)
			)
			(layer "F.Fab")
		)
		(fp_line
			(start 0.12065 -0.3048)
			(end 0.67945 -0.3048)
			(stroke
				(width 0.1)
				(type default)
			)
			(layer "F.Fab")
		)
		(fp_line
			(start 0.12065 -0.2794)
			(end 0.12065 -0.3048)
			(stroke
				(width 0.1)
				(type default)
			)
			(layer "F.Fab")
		)
		(fp_line
			(start -0.12065 -0.2794)
			(end 0.12065 -0.2794)
			(stroke
				(width 0.1)
				(type default)
			)
			(layer "F.Fab")
		)
		(fp_line
			(start 0.120396 0.2794)
			(end -0.12065 0.2794)
			(stroke
				(width 0.1)
				(type default)
			)
			(layer "F.Fab")
		)
		(fp_line
			(start -0.12065 0.2794)
			(end -0.12065 0.3048)
			(stroke
				(width 0.1)
				(type default)
			)
			(layer "F.Fab")
		)
		(fp_line
			(start 0.67945 0.3048)
			(end 0.120396 0.3048)
			(stroke
				(width 0.1)
				(type default)
			)
			(layer "F.Fab")
		)
		(fp_line
			(start 0.120396 0.3048)
			(end 0.120396 0.2794)
			(stroke
				(width 0.1)
				(type default)
			)
			(layer "F.Fab")
		)
		(fp_line
			(start -0.12065 0.3048)
			(end -0.67945 0.3048)
			(stroke
				(width 0.1)
				(type default)
			)
			(layer "F.Fab")
		)
		(fp_line
			(start -0.67945 0.3048)
			(end -0.67945 -0.305054)
			(stroke
				(width 0.1)
				(type default)
			)
			(layer "F.Fab")
		)
		(pad "1" smd circle
			(at -0.40005 0 90)
			(size 0 0)
			(layers "F.Cu" "F.Mask" "F.Paste")
			(net "P3V3_AUX")
		)
		(pad "2" smd circle
			(at 0.40005 0 90)
			(size 0 0)
			(layers "F.Cu" "F.Mask" "F.Paste")
			(net "NIC_ADC_ALERT_N")
		)
	)
)
